(kicad_pcb
	(version 20260206)
	(generator "pcbnew")
	(generator_version "10.0")
	(general
		(thickness 1.6)
		(legacy_teardrops no)
	)
	(paper "A4")
	(title_block
		(title "v1-chassis-manager — T6M_CM_d_v01_1031_1645.brd")
		(comment 1 "Open CloudServer (Microsoft) / footprints 1328-1336 of 2512")
	)
	(layers
		(0 "F.Cu" signal "TOP")
		(4 "In1.Cu" signal "GND1")
		(6 "In2.Cu" signal "IN1")
		(8 "In3.Cu" signal "VCC1")
		(10 "In4.Cu" signal "VCC2")
		(12 "In5.Cu" signal "GND2")
		(14 "In6.Cu" signal "IN2")
		(16 "In7.Cu" signal "IN3")
		(18 "In8.Cu" signal "GND3")
		(2 "B.Cu" signal "BOTTOM")
		(9 "F.Adhes" user "F.Adhesive")
		(11 "B.Adhes" user "B.Adhesive")
		(13 "F.Paste" user "Package Geometry/Pastemask Top")
		(15 "B.Paste" user "Package Geometry/Pastemask Bottom")
		(5 "F.SilkS" user "Ref Des/Silkscreen Top")
		(7 "B.SilkS" user "Ref Des/Silkscreen Bottom")
		(1 "F.Mask" user "Board Geometry/Soldermask Top")
		(3 "B.Mask" user "Board Geometry/Soldermask Bottom")
		(17 "Dwgs.User" user "User.Drawings")
		(19 "Cmts.User" user "User.Comments")
		(21 "Eco1.User" user "User.Eco1")
		(23 "Eco2.User" user "User.Eco2")
		(25 "Edge.Cuts" user "Board Geometry/Outline")
		(27 "Margin" user)
		(31 "F.CrtYd" user "Package Geometry/Place Bound Top")
		(29 "B.CrtYd" user "Package Geometry/Place Bound Bottom")
		(35 "F.Fab" user "Ref Des/Assembly Top")
		(33 "B.Fab" user "Ref Des/Assembly Bottom")
	)
	(footprint ""
		(layer "F.Cu")
		(at 169.77868 -61.181742 90)
		(property "Reference" "L45"
			(at 1.256792 -0.940308 90)
			(unlocked yes)
			(layer "F.SilkS")
			(effects
				(font
					(size 0.7874 0.5842)
					(thickness 0.1524)
				)
				(justify left)
			)
		)
		(property "Value" ""
			(at 0 0 90)
			(layer "F.Fab")
			(effects
				(font
					(size 1.27 1.27)
				)
			)
		)
		(duplicate_pad_numbers_are_jumpers no)
		(fp_line
			(start 0.989838 -2.0066)
			(end 0.989838 2.0066)
			(stroke
				(width 0.1524)
				(type default)
			)
			(layer "F.SilkS")
		)
		(fp_line
			(start -1.015238 -2.0066)
			(end 0.989838 -2.0066)
			(stroke
				(width 0.1524)
				(type default)
			)
			(layer "F.SilkS")
		)
		(fp_line
			(start 0.989838 2.0066)
			(end -1.015238 2.0066)
			(stroke
				(width 0.1524)
				(type default)
			)
			(layer "F.SilkS")
		)
		(fp_line
			(start -1.015238 2.0066)
			(end -1.015238 -2.0066)
			(stroke
				(width 0.1524)
				(type default)
			)
			(layer "F.SilkS")
		)
		(fp_poly
			(pts
				(xy -0.899922 -1.700022) (xy -0.899922 1.700022) (xy -0.8636 1.700022) (xy -0.8636 1.9304) (xy -0.127 1.9304)
				(xy -0.127 1.700022) (xy 0.127 1.700022) (xy 0.127 1.9304) (xy 0.8636 1.9304) (xy 0.8636 1.700022)
				(xy 0.899922 1.700022) (xy 0.899922 -1.700022) (xy 0.8636 -1.700022) (xy 0.8636 -1.9304) (xy 0.127 -1.9304)
				(xy 0.127 -1.700022) (xy -0.127 -1.700022) (xy -0.127 -1.9304) (xy -0.8636 -1.9304) (xy -0.8636 -1.700022)
			)
			(stroke
				(width 0)
				(type default)
			)
			(fill no)
			(layer "F.CrtYd")
		)
		(fp_line
			(start 0.899922 -1.700022)
			(end 0.899922 1.700022)
			(stroke
				(width 0.1)
				(type default)
			)
			(layer "F.Fab")
		)
		(fp_line
			(start -0.899922 -1.700022)
			(end 0.899922 -1.700022)
			(stroke
				(width 0.1)
				(type default)
			)
			(layer "F.Fab")
		)
		(fp_line
			(start 0.899922 1.700022)
			(end -0.899922 1.700022)
			(stroke
				(width 0.1)
				(type default)
			)
			(layer "F.Fab")
		)
		(fp_line
			(start -0.899922 1.700022)
			(end -0.899922 -1.700022)
			(stroke
				(width 0.1)
				(type default)
			)
			(layer "F.Fab")
		)
		(pad "1" smd rect
			(at -0.499872 -1.400048 90)
			(size 0.6096 0.9144)
			(layers "F.Cu" "F.Mask" "F.Paste")
			(net "USB3_DN")
		)
		(pad "2" smd rect
			(at -0.499872 1.400048 90)
			(size 0.6096 0.9144)
			(layers "F.Cu" "F.Mask" "F.Paste")
			(net "USB3_L_DN")
		)
		(pad "3" smd rect
			(at 0.499872 1.400048 90)
			(size 0.6096 0.9144)
			(layers "F.Cu" "F.Mask" "F.Paste")
			(net "USB3_L_DP")
		)
		(pad "4" smd rect
			(at 0.499872 -1.400048 90)
			(size 0.6096 0.9144)
			(layers "F.Cu" "F.Mask" "F.Paste")
			(net "USB3_DP")
		)
	)
	(footprint ""
		(layer "F.Cu")
		(at 38.379654 -112.650016 -90)
		(property "Reference" "R1118"
			(at 4.552696 0.892048 90)
			(unlocked yes)
			(layer "F.SilkS")
			(effects
				(font
					(size 0.7874 0.5842)
					(thickness 0.1524)
				)
				(justify left)
			)
		)
		(property "Value" ""
			(at 0 0 270)
			(layer "F.Fab")
			(effects
				(font
					(size 1.27 1.27)
				)
			)
		)
		(duplicate_pad_numbers_are_jumpers no)
		(fp_line
			(start -0.7874 0.4064)
			(end -0.7874 -0.4064)
			(stroke
				(width 0.1524)
				(type default)
			)
			(layer "F.SilkS")
		)
		(fp_line
			(start 0.7874 0.4064)
			(end -0.7874 0.4064)
			(stroke
				(width 0.1524)
				(type default)
			)
			(layer "F.SilkS")
		)
		(fp_line
			(start -0.7874 -0.4064)
			(end 0.7874 -0.4064)
			(stroke
				(width 0.1524)
				(type default)
			)
			(layer "F.SilkS")
		)
		(fp_line
			(start 0.7874 -0.4064)
			(end 0.7874 0.4064)
			(stroke
				(width 0.1524)
				(type default)
			)
			(layer "F.SilkS")
		)
		(fp_poly
			(pts
				(xy -0.508 0.2794) (xy -0.508 0.2286) (xy -0.635 0.2286) (xy -0.635 -0.254) (xy -0.5334 -0.254)
				(xy -0.5334 -0.2794) (xy 0.5334 -0.2794) (xy 0.5334 -0.254) (xy 0.635 -0.254) (xy 0.635 0.254) (xy 0.5334 0.254)
				(xy 0.5334 0.2794)
			)
			(stroke
				(width 0)
				(type default)
			)
			(fill no)
			(layer "F.CrtYd")
		)
		(pad "1" smd rect
			(at 0.40005 0 270)
			(size 0.4572 0.508)
			(layers "F.Cu" "F.Mask" "F.Paste")
			(net "GND")
		)
		(pad "2" smd rect
			(at -0.40005 0 270)
			(size 0.4572 0.508)
			(layers "F.Cu" "F.Mask" "F.Paste")
			(net "P1V5_NODE1")
		)
	)
	(footprint ""
		(layer "F.Cu")
		(at 71.888604 -9.343898 180)
		(property "Reference" "PC44"
			(at -3.495548 0.070104 0)
			(unlocked yes)
			(layer "F.SilkS")
			(effects
				(font
					(size 0.7874 0.5842)
					(thickness 0.1524)
				)
				(justify left)
			)
		)
		(property "Value" ""
			(at 0 0 180)
			(layer "F.Fab")
			(effects
				(font
					(size 1.27 1.27)
				)
			)
		)
		(duplicate_pad_numbers_are_jumpers no)
		(fp_line
			(start 0.7874 0.4064)
			(end -0.7874 0.4064)
			(stroke
				(width 0.1524)
				(type default)
			)
			(layer "F.SilkS")
		)
		(fp_line
			(start 0.7874 -0.4064)
			(end 0.7874 0.4064)
			(stroke
				(width 0.1524)
				(type default)
			)
			(layer "F.SilkS")
		)
		(fp_line
			(start 0 0.381)
			(end 0 -0.381)
			(stroke
				(width 0.1524)
				(type default)
			)
			(layer "F.SilkS")
		)
		(fp_line
			(start -0.7874 0.4064)
			(end -0.7874 -0.4064)
			(stroke
				(width 0.1524)
				(type default)
			)
			(layer "F.SilkS")
		)
		(fp_line
			(start -0.7874 -0.4064)
			(end 0.7874 -0.4064)
			(stroke
				(width 0.1524)
				(type default)
			)
			(layer "F.SilkS")
		)
		(fp_poly
			(pts
				(xy -0.5334 0.254) (xy -0.635 0.254) (xy -0.635 0.2286) (xy -0.635 -0.254) (xy -0.5334 -0.254) (xy -0.5334 -0.2794)
				(xy 0.5334 -0.2794) (xy 0.5334 -0.254) (xy 0.635 -0.254) (xy 0.635 0.254) (xy 0.5334 0.254) (xy 0.5334 0.2794)
				(xy -0.508 0.2794) (xy -0.5334 0.2794)
			)
			(stroke
				(width 0)
				(type default)
			)
			(fill no)
			(layer "F.CrtYd")
		)
		(pad "1" smd rect
			(at 0.40005 0 180)
			(size 0.4572 0.508)
			(layers "F.Cu" "F.Mask" "F.Paste")
			(net "P12V_AUX")
		)
		(pad "2" smd rect
			(at -0.40005 0 180)
			(size 0.4572 0.508)
			(layers "F.Cu" "F.Mask" "F.Paste")
			(net "GND")
		)
	)
	(footprint ""
		(layer "F.Cu")
		(at 90.753692 -160.942528 180)
		(property "Reference" "U104"
			(at -87.894414 -71.801228 90)
			(unlocked yes)
			(layer "F.SilkS")
			(effects
				(font
					(size 0.7874 0.5842)
					(thickness 0.1524)
				)
			)
		)
		(property "Value" ""
			(at 0 0 180)
			(layer "F.Fab")
			(effects
				(font
					(size 1.27 1.27)
				)
			)
		)
		(duplicate_pad_numbers_are_jumpers no)
		(fp_line
			(start 1.651 1.905)
			(end -1.651 1.905)
			(stroke
				(width 0.1524)
				(type default)
			)
			(layer "F.SilkS")
		)
		(fp_line
			(start 1.651 -1.905)
			(end 1.651 1.905)
			(stroke
				(width 0.1524)
				(type default)
			)
			(layer "F.SilkS")
		)
		(fp_line
			(start -1.651 1.905)
			(end -1.651 -1.905)
			(stroke
				(width 0.1524)
				(type default)
			)
			(layer "F.SilkS")
		)
		(fp_line
			(start -1.651 -1.905)
			(end 1.651 -1.905)
			(stroke
				(width 0.1524)
				(type default)
			)
			(layer "F.SilkS")
		)
		(fp_poly
			(pts
				(xy -1.524 0.7112) (xy -1.524 1.7526) (xy -0.508 1.7526) (xy -0.508 0.6985) (xy 0.508 0.6985) (xy 0.508 1.7526)
				(xy 1.524 1.7526) (xy 1.524 0.6985) (xy 1.524 -0.6985) (xy 0.508 -0.6985) (xy 0.508 -1.7526) (xy -0.508 -1.7526)
				(xy -0.508 -0.6985) (xy -1.524 -0.6985) (xy -1.524 0.6985)
			)
			(stroke
				(width 0)
				(type default)
			)
			(fill no)
			(layer "F.CrtYd")
		)
		(fp_text user "S"
			(at 1.998726 1.213358 0)
			(unlocked yes)
			(layer "F.SilkS")
			(effects
				(font
					(size 0.635 0.4064)
					(thickness 0.1524)
				)
			)
		)
		(fp_text user "D"
			(at 1.92913 -0.415544 0)
			(unlocked yes)
			(layer "F.SilkS")
			(effects
				(font
					(size 0.635 0.4064)
					(thickness 0.1524)
				)
			)
		)
		(fp_text user "G"
			(at -1.477264 2.459228 0)
			(unlocked yes)
			(layer "F.SilkS")
			(effects
				(font
					(size 0.635 0.4064)
					(thickness 0.1524)
				)
			)
		)
		(pad "D" smd rect
			(at 0 -1.1176 180)
			(size 1.016 1.27)
			(layers "F.Cu" "F.Mask" "F.Paste")
			(net "N52410998")
		)
		(pad "G" smd rect
			(at -1.016 1.1176 180)
			(size 1.016 1.27)
			(layers "F.Cu" "F.Mask" "F.Paste")
			(net "POWER_SW1_PWR_CTR_N")
		)
		(pad "S" smd rect
			(at 1.016 1.1176 180)
			(size 1.016 1.27)
			(layers "F.Cu" "F.Mask" "F.Paste")
			(net "GND")
		)
	)
	(footprint ""
		(layer "F.Cu")
		(at -71.458328 -265.390884)
		(property "Reference" "BT1_BATTERY1"
			(at 9.578848 0.097282 0)
			(unlocked yes)
			(layer "B.SilkS")
			(effects
				(font
					(size 0.7874 0.5842)
					(thickness 0.1524)
				)
				(justify left mirror)
			)
		)
		(property "Value" ""
			(at 0 0 0)
			(layer "F.Fab")
			(effects
				(font
					(size 1.27 1.27)
				)
			)
		)
		(duplicate_pad_numbers_are_jumpers no)
		(fp_poly
			(pts
				(arc
					(start 0.3302 0)
					(mid -0.3302 0)
					(end 0.3302 0)
				)
			)
			(stroke
				(width 0)
				(type default)
			)
			(fill no)
			(layer "B.CrtYd")
		)
		(pad "1" thru_hole circle
			(at 0 0)
			(size 0.508 0.508)
			(drill 0.254)
			(layers "*.Cu" "*.Mask")
			(remove_unused_layers no)
			(net "Net_1677")
			(clearance 0.127)
			(thermal_gap 0.127)
			(padstack
				(mode front_inner_back)
				(layer "Inner"
					(shape circle)
					(size 0.508 0.508)
					(clearance 0.127)
				)
				(layer "B.Cu"
					(shape circle)
					(size 0.6604 0.6604)
					(clearance 0.0508)
				)
			)
		)
	)
	(footprint ""
		(layer "F.Cu")
		(at 41.316402 -145.804382 -90)
		(property "Reference" "R550"
			(at 0.86106 6.618732 90)
			(unlocked yes)
			(layer "F.SilkS")
			(effects
				(font
					(size 0.7874 0.5842)
					(thickness 0.1524)
				)
				(justify left)
			)
		)
		(property "Value" ""
			(at 0 0 270)
			(layer "F.Fab")
			(effects
				(font
					(size 1.27 1.27)
				)
			)
		)
		(duplicate_pad_numbers_are_jumpers no)
		(fp_line
			(start -0.7874 0.4064)
			(end -0.7874 -0.4064)
			(stroke
				(width 0.1524)
				(type default)
			)
			(layer "F.SilkS")
		)
		(fp_line
			(start 0.7874 0.4064)
			(end -0.7874 0.4064)
			(stroke
				(width 0.1524)
				(type default)
			)
			(layer "F.SilkS")
		)
		(fp_line
			(start -0.7874 -0.4064)
			(end 0.7874 -0.4064)
			(stroke
				(width 0.1524)
				(type default)
			)
			(layer "F.SilkS")
		)
		(fp_line
			(start 0.7874 -0.4064)
			(end 0.7874 0.4064)
			(stroke
				(width 0.1524)
				(type default)
			)
			(layer "F.SilkS")
		)
		(fp_poly
			(pts
				(xy -0.508 0.2794) (xy -0.508 0.2286) (xy -0.635 0.2286) (xy -0.635 -0.254) (xy -0.5334 -0.254)
				(xy -0.5334 -0.2794) (xy 0.5334 -0.2794) (xy 0.5334 -0.254) (xy 0.635 -0.254) (xy 0.635 0.254) (xy 0.5334 0.254)
				(xy 0.5334 0.2794)
			)
			(stroke
				(width 0)
				(type default)
			)
			(fill no)
			(layer "F.CrtYd")
		)
		(pad "1" smd rect
			(at 0.40005 0 270)
			(size 0.4572 0.508)
			(layers "F.Cu" "F.Mask" "F.Paste")
			(net "P3V3_NODE1")
		)
		(pad "2" smd rect
			(at -0.40005 0 270)
			(size 0.4572 0.508)
			(layers "F.Cu" "F.Mask" "F.Paste")
			(net "LAN1_NC_SI_RXD1")
		)
	)
	(footprint ""
		(layer "F.Cu")
		(at 68.594732 -9.513062)
		(property "Reference" "PC46"
			(at 0.119634 -1.117092 90)
			(unlocked yes)
			(layer "F.SilkS")
			(effects
				(font
					(size 0.7874 0.5842)
					(thickness 0.1524)
				)
				(justify left)
			)
		)
		(property "Value" ""
			(at 0 0 0)
			(layer "F.Fab")
			(effects
				(font
					(size 1.27 1.27)
				)
			)
		)
		(duplicate_pad_numbers_are_jumpers no)
		(fp_line
			(start -0.7874 -0.4064)
			(end 0.7874 -0.4064)
			(stroke
				(width 0.1524)
				(type default)
			)
			(layer "F.SilkS")
		)
		(fp_line
			(start -0.7874 0.4064)
			(end -0.7874 -0.4064)
			(stroke
				(width 0.1524)
				(type default)
			)
			(layer "F.SilkS")
		)
		(fp_line
			(start 0 0.381)
			(end 0 -0.381)
			(stroke
				(width 0.1524)
				(type default)
			)
			(layer "F.SilkS")
		)
		(fp_line
			(start 0.7874 -0.4064)
			(end 0.7874 0.4064)
			(stroke
				(width 0.1524)
				(type default)
			)
			(layer "F.SilkS")
		)
		(fp_line
			(start 0.7874 0.4064)
			(end -0.7874 0.4064)
			(stroke
				(width 0.1524)
				(type default)
			)
			(layer "F.SilkS")
		)
		(fp_poly
			(pts
				(xy -0.5334 0.254) (xy -0.635 0.254) (xy -0.635 0.2286) (xy -0.635 -0.254) (xy -0.5334 -0.254) (xy -0.5334 -0.2794)
				(xy 0.5334 -0.2794) (xy 0.5334 -0.254) (xy 0.635 -0.254) (xy 0.635 0.254) (xy 0.5334 0.254) (xy 0.5334 0.2794)
				(xy -0.508 0.2794) (xy -0.5334 0.2794)
			)
			(stroke
				(width 0)
				(type default)
			)
			(fill no)
			(layer "F.CrtYd")
		)
		(pad "1" smd rect
			(at 0.40005 0)
			(size 0.4572 0.508)
			(layers "F.Cu" "F.Mask" "F.Paste")
			(net "P5V_STB_NODE1")
		)
		(pad "2" smd rect
			(at -0.40005 0)
			(size 0.4572 0.508)
			(layers "F.Cu" "F.Mask" "F.Paste")
			(net "GND")
		)
	)
	(footprint ""
		(layer "F.Cu")
		(at 14.885416 -65.290446)
		(property "Reference" "C508"
			(at -2.683256 -1.039368 0)
			(unlocked yes)
			(layer "F.SilkS")
			(effects
				(font
					(size 0.7874 0.5842)
					(thickness 0.1524)
				)
				(justify left)
			)
		)
		(property "Value" ""
			(at 0 0 0)
			(layer "F.Fab")
			(effects
				(font
					(size 1.27 1.27)
				)
			)
		)
		(duplicate_pad_numbers_are_jumpers no)
		(fp_line
			(start -0.7874 -0.4064)
			(end 0.7874 -0.4064)
			(stroke
				(width 0.1524)
				(type default)
			)
			(layer "F.SilkS")
		)
		(fp_line
			(start -0.7874 0.4064)
			(end -0.7874 -0.4064)
			(stroke
				(width 0.1524)
				(type default)
			)
			(layer "F.SilkS")
		)
		(fp_line
			(start 0 0.381)
			(end 0 -0.381)
			(stroke
				(width 0.1524)
				(type default)
			)
			(layer "F.SilkS")
		)
		(fp_line
			(start 0.7874 -0.4064)
			(end 0.7874 0.4064)
			(stroke
				(width 0.1524)
				(type default)
			)
			(layer "F.SilkS")
		)
		(fp_line
			(start 0.7874 0.4064)
			(end -0.7874 0.4064)
			(stroke
				(width 0.1524)
				(type default)
			)
			(layer "F.SilkS")
		)
		(fp_poly
			(pts
				(xy -0.5334 0.254) (xy -0.635 0.254) (xy -0.635 0.2286) (xy -0.635 -0.254) (xy -0.5334 -0.254) (xy -0.5334 -0.2794)
				(xy 0.5334 -0.2794) (xy 0.5334 -0.254) (xy 0.635 -0.254) (xy 0.635 0.254) (xy 0.5334 0.254) (xy 0.5334 0.2794)
				(xy -0.508 0.2794) (xy -0.5334 0.2794)
			)
			(stroke
				(width 0)
				(type default)
			)
			(fill no)
			(layer "F.CrtYd")
		)
		(pad "1" smd rect
			(at 0.40005 0)
			(size 0.4572 0.508)
			(layers "F.Cu" "F.Mask" "F.Paste")
			(net "CRT_DDCCLK")
		)
		(pad "2" smd rect
			(at -0.40005 0)
			(size 0.4572 0.508)
			(layers "F.Cu" "F.Mask" "F.Paste")
			(net "GND")
		)
	)
	(footprint ""
		(layer "F.Cu")
		(at 87.617554 -78.416658)
		(property "Reference" "L4"
			(at 2.681986 0.21717 0)
			(unlocked yes)
			(layer "F.SilkS")
			(effects
				(font
					(size 0.7874 0.5842)
					(thickness 0.1524)
				)
				(justify left)
			)
		)
		(property "Value" ""
			(at 0 0 0)
			(layer "F.Fab")
			(effects
				(font
					(size 1.27 1.27)
				)
			)
		)
		(duplicate_pad_numbers_are_jumpers no)
		(fp_line
			(start -0.7874 -0.4064)
			(end 0.7874 -0.4064)
			(stroke
				(width 0.1524)
				(type default)
			)
			(layer "F.SilkS")
		)
		(fp_line
			(start -0.7874 0.4064)
			(end -0.7874 -0.4064)
			(stroke
				(width 0.1524)
				(type default)
			)
			(layer "F.SilkS")
		)
		(fp_line
			(start -0.0889 0.4064)
			(end -0.0889 -0.4064)
			(stroke
				(width 0.1524)
				(type default)
			)
			(layer "F.SilkS")
		)
		(fp_line
			(start 0.0889 0.4064)
			(end 0.0889 -0.4064)
			(stroke
				(width 0.1524)
				(type default)
			)
			(layer "F.SilkS")
		)
		(fp_line
			(start 0.7874 -0.4064)
			(end 0.7874 0.4064)
			(stroke
				(width 0.1524)
				(type default)
			)
			(layer "F.SilkS")
		)
		(fp_line
			(start 0.7874 0.4064)
			(end -0.7874 0.4064)
			(stroke
				(width 0.1524)
				(type default)
			)
			(layer "F.SilkS")
		)
		(fp_poly
			(pts
				(xy -0.5334 0.254) (xy -0.635 0.254) (xy -0.635 0.2286) (xy -0.635 -0.254) (xy -0.5334 -0.254) (xy -0.5334 -0.2794)
				(xy 0.5334 -0.2794) (xy 0.5334 -0.254) (xy 0.635 -0.254) (xy 0.635 0.254) (xy 0.5334 0.254) (xy 0.5334 0.2794)
				(xy -0.508 0.2794) (xy -0.5334 0.2794)
			)
			(stroke
				(width 0)
				(type default)
			)
			(fill no)
			(layer "F.CrtYd")
		)
		(pad "1" smd rect
			(at 0.40005 0)
			(size 0.4572 0.508)
			(layers "F.Cu" "F.Mask" "F.Paste")
			(net "P1V05_NODE1")
		)
		(pad "2" smd rect
			(at -0.40005 0)
			(size 0.4572 0.508)
			(layers "F.Cu" "F.Mask" "F.Paste")
			(net "P1V05_VCCPLLCPU0SIO_NODE1")
		)
	)
)
